(kicad_pcb
	(version 20260206)
	(generator "pcbnew")
	(generator_version "10.0")
	(general
		(thickness 1.6)
		(legacy_teardrops no)
	)
	(paper "A4")
	(title_block
		(title "pdpb — Lightning_PDPB_BRD.brd")
		(comment 1 "Lightning (Wiwynn / Facebook NVMe JBOF) / footprints 485-491 of 1140")
	)
	(layers
		(0 "F.Cu" signal "TOP")
		(4 "In1.Cu" signal "L2GND")
		(6 "In2.Cu" signal "L3")
		(8 "In3.Cu" signal "L4VCC")
		(10 "In4.Cu" signal "L5VCC")
		(12 "In5.Cu" signal "L6")
		(14 "In6.Cu" signal "L7GND")
		(2 "B.Cu" signal "BOTTOM")
		(9 "F.Adhes" user "F.Adhesive")
		(11 "B.Adhes" user "B.Adhesive")
		(13 "F.Paste" user "Package Geometry/Pastemask Top")
		(15 "B.Paste" user "Package Geometry/Pastemask Bottom")
		(5 "F.SilkS" user "Ref Des/Silkscreen Top")
		(7 "B.SilkS" user "Ref Des/Silkscreen Bottom")
		(1 "F.Mask" user "Board Geometry/Soldermask Top")
		(3 "B.Mask" user "Board Geometry/Soldermask Bottom")
		(17 "Dwgs.User" user "User.Drawings")
		(19 "Cmts.User" user "User.Comments")
		(21 "Eco1.User" user "User.Eco1")
		(23 "Eco2.User" user "User.Eco2")
		(25 "Edge.Cuts" user "Board Geometry/Outline")
		(27 "Margin" user)
		(31 "F.CrtYd" user "Package Geometry/Place Bound Top")
		(29 "B.CrtYd" user "Package Geometry/Place Bound Bottom")
		(35 "F.Fab" user "Ref Des/Assembly Top")
		(33 "B.Fab" user "Ref Des/Assembly Bottom")
	)
	(footprint ""
		(layer "F.Cu")
		(at 27.94 -374.65 180)
		(property "Reference" "R333"
			(at 0 0 180)
			(layer "F.SilkS")
			(hide yes)
			(effects
				(font
					(size 1.27 1.27)
				)
			)
		)
		(property "Value" "4K7R2J-2-GP"
			(at 0.064008 -3.993896 180)
			(unlocked yes)
			(layer "F.Fab")
			(hide yes)
			(effects
				(font
					(size 1.016 1.016)
					(thickness 0.1524)
				)
			)
		)
		(property "Device Type" "R402H16"
			(at 0.064008 -5.517896 180)
			(unlocked yes)
			(layer "F.Fab")
			(hide yes)
			(effects
				(font
					(size 1.016 1.016)
					(thickness 0.1524)
				)
			)
		)
		(duplicate_pad_numbers_are_jumpers no)
		(fp_line
			(start 0.508 -0.9398)
			(end -0.508 -0.9398)
			(stroke
				(width 0.1524)
				(type default)
			)
			(layer "F.SilkS")
		)
		(fp_line
			(start -0.508 -0.9398)
			(end -0.508 0.9398)
			(stroke
				(width 0.1524)
				(type default)
			)
			(layer "F.SilkS")
		)
		(fp_rect
			(start -0.508 0.9398)
			(end 0.508 -0.9398)
			(stroke
				(width 0)
				(type default)
			)
			(fill no)
			(layer "F.CrtYd")
		)
		(fp_rect
			(start -0.508 0.9398)
			(end 0.508 -0.9398)
			(stroke
				(width 0)
				(type default)
			)
			(fill no)
			(layer "F.Fab")
		)
		(pad "1" smd custom
			(at 0 -0.4445 180)
			(size 0.1397 0.1397)
			(layers "F.Cu" "F.Mask" "F.Paste")
			(net "P3V3")
			(options
				(clearance outline)
				(anchor circle)
			)
			(primitives
				(gr_poly
					(pts
						(arc
							(start -0.1778 -0.2794)
							(mid -0.249642 -0.249642)
							(end -0.2794 -0.1778)
						)
						(arc
							(start -0.2794 0.1778)
							(mid -0.249642 0.249642)
							(end -0.1778 0.2794)
						)
						(arc
							(start 0.1778 0.2794)
							(mid 0.249642 0.249642)
							(end 0.2794 0.1778)
						)
						(arc
							(start 0.2794 -0.1778)
							(mid 0.249642 -0.249642)
							(end 0.1778 -0.2794)
						)
					)
					(width 0)
					(fill yes)
				)
			)
		)
		(pad "2" smd custom
			(at 0 0.4445 180)
			(size 0.1397 0.1397)
			(layers "F.Cu" "F.Mask" "F.Paste")
			(net "I2C_B_TMP4_A0")
			(options
				(clearance outline)
				(anchor circle)
			)
			(primitives
				(gr_poly
					(pts
						(arc
							(start -0.1778 -0.2794)
							(mid -0.249642 -0.249642)
							(end -0.2794 -0.1778)
						)
						(arc
							(start -0.2794 0.1778)
							(mid -0.249642 0.249642)
							(end -0.1778 0.2794)
						)
						(arc
							(start 0.1778 0.2794)
							(mid 0.249642 0.249642)
							(end 0.2794 0.1778)
						)
						(arc
							(start 0.2794 -0.1778)
							(mid 0.249642 -0.249642)
							(end 0.1778 -0.2794)
						)
					)
					(width 0)
					(fill yes)
				)
			)
		)
	)
	(footprint ""
		(layer "F.Cu")
		(at 82.931 -102.7176 90)
		(property "Reference" "R9357"
			(at 0 0 90)
			(layer "F.SilkS")
			(hide yes)
			(effects
				(font
					(size 1.27 1.27)
				)
			)
		)
		(property "Value" "2D2R2F-GP"
			(at 0.064008 -3.993896 90)
			(unlocked yes)
			(layer "F.Fab")
			(hide yes)
			(effects
				(font
					(size 1.016 1.016)
					(thickness 0.1524)
				)
			)
		)
		(property "Device Type" "R402H16"
			(at 0.064008 -5.517896 90)
			(unlocked yes)
			(layer "F.Fab")
			(hide yes)
			(effects
				(font
					(size 1.016 1.016)
					(thickness 0.1524)
				)
			)
		)
		(duplicate_pad_numbers_are_jumpers no)
		(fp_line
			(start 0.508 -0.9398)
			(end -0.508 -0.9398)
			(stroke
				(width 0.1524)
				(type default)
			)
			(layer "F.SilkS")
		)
		(fp_line
			(start -0.508 -0.9398)
			(end -0.508 0.9398)
			(stroke
				(width 0.1524)
				(type default)
			)
			(layer "F.SilkS")
		)
		(fp_rect
			(start -0.508 0.9398)
			(end 0.508 -0.9398)
			(stroke
				(width 0)
				(type default)
			)
			(fill no)
			(layer "F.CrtYd")
		)
		(fp_rect
			(start -0.508 0.9398)
			(end 0.508 -0.9398)
			(stroke
				(width 0)
				(type default)
			)
			(fill no)
			(layer "F.Fab")
		)
		(pad "1" smd custom
			(at 0 -0.4445 90)
			(size 0.1397 0.1397)
			(layers "F.Cu" "F.Mask" "F.Paste")
			(net "VDD_DIFF_4")
			(options
				(clearance outline)
				(anchor circle)
			)
			(primitives
				(gr_poly
					(pts
						(arc
							(start -0.1778 -0.2794)
							(mid -0.249642 -0.249642)
							(end -0.2794 -0.1778)
						)
						(arc
							(start -0.2794 0.1778)
							(mid -0.249642 0.249642)
							(end -0.1778 0.2794)
						)
						(arc
							(start 0.1778 0.2794)
							(mid 0.249642 0.249642)
							(end 0.2794 0.1778)
						)
						(arc
							(start 0.2794 -0.1778)
							(mid 0.249642 -0.249642)
							(end 0.1778 -0.2794)
						)
					)
					(width 0)
					(fill yes)
				)
			)
		)
		(pad "2" smd custom
			(at 0 0.4445 90)
			(size 0.1397 0.1397)
			(layers "F.Cu" "F.Mask" "F.Paste")
			(net "VDDR_4")
			(options
				(clearance outline)
				(anchor circle)
			)
			(primitives
				(gr_poly
					(pts
						(arc
							(start -0.1778 -0.2794)
							(mid -0.249642 -0.249642)
							(end -0.2794 -0.1778)
						)
						(arc
							(start -0.2794 0.1778)
							(mid -0.249642 0.249642)
							(end -0.1778 0.2794)
						)
						(arc
							(start 0.1778 0.2794)
							(mid 0.249642 0.249642)
							(end 0.2794 0.1778)
						)
						(arc
							(start 0.2794 -0.1778)
							(mid 0.249642 -0.249642)
							(end 0.1778 -0.2794)
						)
					)
					(width 0)
					(fill yes)
				)
			)
		)
	)
	(footprint ""
		(layer "F.Cu")
		(at 216.789 -491.6932 -90)
		(property "Reference" "R380"
			(at 0 0 270)
			(layer "F.SilkS")
			(hide yes)
			(effects
				(font
					(size 1.27 1.27)
				)
			)
		)
		(property "Value" "0R2J-2-GP"
			(at 0.064008 -3.993896 270)
			(unlocked yes)
			(layer "F.Fab")
			(hide yes)
			(effects
				(font
					(size 1.016 1.016)
					(thickness 0.1524)
				)
			)
		)
		(property "Device Type" "R402H16"
			(at 0.064008 -5.517896 270)
			(unlocked yes)
			(layer "F.Fab")
			(hide yes)
			(effects
				(font
					(size 1.016 1.016)
					(thickness 0.1524)
				)
			)
		)
		(duplicate_pad_numbers_are_jumpers no)
		(fp_line
			(start -0.508 -0.9398)
			(end -0.508 0.9398)
			(stroke
				(width 0.1524)
				(type default)
			)
			(layer "F.SilkS")
		)
		(fp_line
			(start 0.508 -0.9398)
			(end -0.508 -0.9398)
			(stroke
				(width 0.1524)
				(type default)
			)
			(layer "F.SilkS")
		)
		(fp_rect
			(start -0.508 0.9398)
			(end 0.508 -0.9398)
			(stroke
				(width 0)
				(type default)
			)
			(fill no)
			(layer "F.CrtYd")
		)
		(fp_rect
			(start -0.508 0.9398)
			(end 0.508 -0.9398)
			(stroke
				(width 0)
				(type default)
			)
			(fill no)
			(layer "F.Fab")
		)
		(pad "1" smd custom
			(at 0 -0.4445 270)
			(size 0.1397 0.1397)
			(layers "F.Cu" "F.Mask" "F.Paste")
			(net "SCL_DR0_R")
			(options
				(clearance outline)
				(anchor circle)
			)
			(primitives
				(gr_poly
					(pts
						(arc
							(start -0.1778 -0.2794)
							(mid -0.249642 -0.249642)
							(end -0.2794 -0.1778)
						)
						(arc
							(start -0.2794 0.1778)
							(mid -0.249642 0.249642)
							(end -0.1778 0.2794)
						)
						(arc
							(start 0.1778 0.2794)
							(mid 0.249642 0.249642)
							(end 0.2794 0.1778)
						)
						(arc
							(start 0.2794 -0.1778)
							(mid 0.249642 -0.249642)
							(end 0.1778 -0.2794)
						)
					)
					(width 0)
					(fill yes)
				)
			)
		)
		(pad "2" smd custom
			(at 0 0.4445 270)
			(size 0.1397 0.1397)
			(layers "F.Cu" "F.Mask" "F.Paste")
			(net "SCL_DR0")
			(options
				(clearance outline)
				(anchor circle)
			)
			(primitives
				(gr_poly
					(pts
						(arc
							(start -0.1778 -0.2794)
							(mid -0.249642 -0.249642)
							(end -0.2794 -0.1778)
						)
						(arc
							(start -0.2794 0.1778)
							(mid -0.249642 0.249642)
							(end -0.1778 0.2794)
						)
						(arc
							(start 0.1778 0.2794)
							(mid 0.249642 0.249642)
							(end 0.2794 0.1778)
						)
						(arc
							(start 0.2794 -0.1778)
							(mid 0.249642 -0.249642)
							(end 0.1778 -0.2794)
						)
					)
					(width 0)
					(fill yes)
				)
			)
		)
	)
	(footprint ""
		(layer "F.Cu")
		(at 87.503 -211.963 180)
		(property "Reference" "C8929"
			(at 0 0 180)
			(layer "F.SilkS")
			(hide yes)
			(effects
				(font
					(size 1.27 1.27)
				)
			)
		)
		(property "Value" "SCD1U16V2KX-3GP"
			(at 1.1811 -2.7051 180)
			(unlocked yes)
			(layer "F.Fab")
			(hide yes)
			(effects
				(font
					(size 1.016 1.016)
					(thickness 0.1524)
				)
			)
		)
		(property "Device Type" "C402H22"
			(at 1.1811 -4.2291 180)
			(unlocked yes)
			(layer "F.Fab")
			(hide yes)
			(effects
				(font
					(size 1.016 1.016)
					(thickness 0.1524)
				)
			)
		)
		(duplicate_pad_numbers_are_jumpers no)
		(fp_rect
			(start -0.4318 0.9525)
			(end 0.4318 -0.9525)
			(stroke
				(width 0)
				(type default)
			)
			(fill no)
			(layer "F.CrtYd")
		)
		(fp_rect
			(start -0.4318 0.9525)
			(end 0.4318 -0.9525)
			(stroke
				(width 0)
				(type default)
			)
			(fill no)
			(layer "F.Fab")
		)
		(pad "1" smd custom
			(at 0 -0.4445 180)
			(size 0.1524 0.1524)
			(layers "F.Cu" "F.Mask" "F.Paste")
			(net "VDDR_3")
			(options
				(clearance outline)
				(anchor circle)
			)
			(primitives
				(gr_poly
					(pts
						(arc
							(start 0.3048 -0.2032)
							(mid 0.275042 -0.275042)
							(end 0.2032 -0.3048)
						)
						(arc
							(start -0.2032 -0.3048)
							(mid -0.275042 -0.275042)
							(end -0.3048 -0.2032)
						)
						(arc
							(start -0.3048 0.2032)
							(mid -0.275042 0.275042)
							(end -0.2032 0.3048)
						)
						(arc
							(start 0.2032 0.3048)
							(mid 0.275042 0.275042)
							(end 0.3048 0.2032)
						)
					)
					(width 0)
					(fill yes)
				)
			)
		)
		(pad "2" smd custom
			(at 0 0.4445 180)
			(size 0.1524 0.1524)
			(layers "F.Cu" "F.Mask" "F.Paste")
			(net "GND")
			(options
				(clearance outline)
				(anchor circle)
			)
			(primitives
				(gr_poly
					(pts
						(arc
							(start 0.3048 -0.2032)
							(mid 0.275042 -0.275042)
							(end 0.2032 -0.3048)
						)
						(arc
							(start -0.2032 -0.3048)
							(mid -0.275042 -0.275042)
							(end -0.3048 -0.2032)
						)
						(arc
							(start -0.3048 0.2032)
							(mid -0.275042 0.275042)
							(end -0.2032 0.3048)
						)
						(arc
							(start 0.2032 0.3048)
							(mid 0.275042 0.275042)
							(end 0.3048 0.2032)
						)
					)
					(width 0)
					(fill yes)
				)
			)
		)
	)
	(footprint ""
		(layer "F.Cu")
		(at 40.321484 -248.157746 -90)
		(property "Reference" "R9942"
			(at 0 0 270)
			(layer "F.SilkS")
			(hide yes)
			(effects
				(font
					(size 1.27 1.27)
				)
			)
		)
		(property "Value" "4K7R2J-2-GP"
			(at 0.064008 -3.993896 270)
			(unlocked yes)
			(layer "F.Fab")
			(hide yes)
			(effects
				(font
					(size 1.016 1.016)
					(thickness 0.1524)
				)
			)
		)
		(property "Device Type" "R402H16"
			(at 0.064008 -5.517896 270)
			(unlocked yes)
			(layer "F.Fab")
			(hide yes)
			(effects
				(font
					(size 1.016 1.016)
					(thickness 0.1524)
				)
			)
		)
		(duplicate_pad_numbers_are_jumpers no)
		(fp_line
			(start -0.508 -0.9398)
			(end -0.508 0.9398)
			(stroke
				(width 0.1524)
				(type default)
			)
			(layer "F.SilkS")
		)
		(fp_line
			(start 0.508 -0.9398)
			(end -0.508 -0.9398)
			(stroke
				(width 0.1524)
				(type default)
			)
			(layer "F.SilkS")
		)
		(fp_rect
			(start -0.508 0.9398)
			(end 0.508 -0.9398)
			(stroke
				(width 0)
				(type default)
			)
			(fill no)
			(layer "F.CrtYd")
		)
		(fp_rect
			(start -0.508 0.9398)
			(end 0.508 -0.9398)
			(stroke
				(width 0)
				(type default)
			)
			(fill no)
			(layer "F.Fab")
		)
		(pad "1" smd custom
			(at 0 -0.4445 270)
			(size 0.1397 0.1397)
			(layers "F.Cu" "F.Mask" "F.Paste")
			(net "P3V3")
			(options
				(clearance outline)
				(anchor circle)
			)
			(primitives
				(gr_poly
					(pts
						(arc
							(start -0.1778 -0.2794)
							(mid -0.249642 -0.249642)
							(end -0.2794 -0.1778)
						)
						(arc
							(start -0.2794 0.1778)
							(mid -0.249642 0.249642)
							(end -0.1778 0.2794)
						)
						(arc
							(start 0.1778 0.2794)
							(mid 0.249642 0.249642)
							(end 0.2794 0.1778)
						)
						(arc
							(start 0.2794 -0.1778)
							(mid 0.249642 -0.249642)
							(end 0.1778 -0.2794)
						)
					)
					(width 0)
					(fill yes)
				)
			)
		)
		(pad "2" smd custom
			(at 0 0.4445 270)
			(size 0.1397 0.1397)
			(layers "F.Cu" "F.Mask" "F.Paste")
			(net "SSD_ACT_DR7_MOS_N")
			(options
				(clearance outline)
				(anchor circle)
			)
			(primitives
				(gr_poly
					(pts
						(arc
							(start -0.1778 -0.2794)
							(mid -0.249642 -0.249642)
							(end -0.2794 -0.1778)
						)
						(arc
							(start -0.2794 0.1778)
							(mid -0.249642 0.249642)
							(end -0.1778 0.2794)
						)
						(arc
							(start 0.1778 0.2794)
							(mid 0.249642 0.249642)
							(end 0.2794 0.1778)
						)
						(arc
							(start 0.2794 -0.1778)
							(mid 0.249642 -0.249642)
							(end 0.1778 -0.2794)
						)
					)
					(width 0)
					(fill yes)
				)
			)
		)
	)
	(footprint ""
		(layer "F.Cu")
		(at 106.045 -436.88 180)
		(property "Reference" "C111"
			(at 0 0 180)
			(layer "F.SilkS")
			(hide yes)
			(effects
				(font
					(size 1.27 1.27)
				)
			)
		)
		(property "Value" "SC1KP50V2KX-1GP"
			(at 1.1811 -2.7051 180)
			(unlocked yes)
			(layer "F.Fab")
			(hide yes)
			(effects
				(font
					(size 1.016 1.016)
					(thickness 0.1524)
				)
			)
		)
		(property "Device Type" "C402H22"
			(at 1.1811 -4.2291 180)
			(unlocked yes)
			(layer "F.Fab")
			(hide yes)
			(effects
				(font
					(size 1.016 1.016)
					(thickness 0.1524)
				)
			)
		)
		(duplicate_pad_numbers_are_jumpers no)
		(fp_rect
			(start -0.4318 0.9525)
			(end 0.4318 -0.9525)
			(stroke
				(width 0)
				(type default)
			)
			(fill no)
			(layer "F.CrtYd")
		)
		(fp_rect
			(start -0.4318 0.9525)
			(end 0.4318 -0.9525)
			(stroke
				(width 0)
				(type default)
			)
			(fill no)
			(layer "F.Fab")
		)
		(pad "1" smd custom
			(at 0 -0.4445 180)
			(size 0.1524 0.1524)
			(layers "F.Cu" "F.Mask" "F.Paste")
			(net "SSD0_CLK0_OE_R_N")
			(options
				(clearance outline)
				(anchor circle)
			)
			(primitives
				(gr_poly
					(pts
						(arc
							(start 0.3048 -0.2032)
							(mid 0.275042 -0.275042)
							(end 0.2032 -0.3048)
						)
						(arc
							(start -0.2032 -0.3048)
							(mid -0.275042 -0.275042)
							(end -0.3048 -0.2032)
						)
						(arc
							(start -0.3048 0.2032)
							(mid -0.275042 0.275042)
							(end -0.2032 0.3048)
						)
						(arc
							(start 0.2032 0.3048)
							(mid 0.275042 0.275042)
							(end 0.3048 0.2032)
						)
					)
					(width 0)
					(fill yes)
				)
			)
		)
		(pad "2" smd custom
			(at 0 0.4445 180)
			(size 0.1524 0.1524)
			(layers "F.Cu" "F.Mask" "F.Paste")
			(net "GND")
			(options
				(clearance outline)
				(anchor circle)
			)
			(primitives
				(gr_poly
					(pts
						(arc
							(start 0.3048 -0.2032)
							(mid 0.275042 -0.275042)
							(end 0.2032 -0.3048)
						)
						(arc
							(start -0.2032 -0.3048)
							(mid -0.275042 -0.275042)
							(end -0.3048 -0.2032)
						)
						(arc
							(start -0.3048 0.2032)
							(mid -0.275042 0.275042)
							(end -0.2032 0.3048)
						)
						(arc
							(start 0.2032 0.3048)
							(mid 0.275042 0.275042)
							(end 0.3048 0.2032)
						)
					)
					(width 0)
					(fill yes)
				)
			)
		)
	)
	(footprint ""
		(layer "F.Cu")
		(at 221.615 -165.354 180)
		(property "Reference" "PC1229"
			(at 0 0 180)
			(layer "F.SilkS")
			(hide yes)
			(effects
				(font
					(size 1.27 1.27)
				)
			)
		)
		(property "Value" "SCD1U25V3KX-GP"
			(at 0 -2.8194 180)
			(unlocked yes)
			(layer "F.Fab")
			(hide yes)
			(effects
				(font
					(size 1.016 1.016)
					(thickness 0.1524)
				)
			)
		)
		(property "Device Type" "C603H36"
			(at 0 -4.3434 180)
			(unlocked yes)
			(layer "F.Fab")
			(hide yes)
			(effects
				(font
					(size 1.016 1.016)
					(thickness 0.1524)
				)
			)
		)
		(duplicate_pad_numbers_are_jumpers no)
		(fp_line
			(start 0.508 0)
			(end -0.508 0)
			(stroke
				(width 0.2032)
				(type default)
			)
			(layer "F.SilkS")
		)
		(fp_rect
			(start -0.5842 1.3335)
			(end 0.5842 -1.3335)
			(stroke
				(width 0)
				(type default)
			)
			(fill no)
			(layer "F.CrtYd")
		)
		(fp_rect
			(start -0.5842 1.3335)
			(end 0.5842 -1.3335)
			(stroke
				(width 0)
				(type default)
			)
			(fill no)
			(layer "F.Fab")
		)
		(pad "1" smd custom
			(at 0 -0.762 180)
			(size 0.2159 0.2159)
			(layers "F.Cu" "F.Mask" "F.Paste")
			(net "P3V3")
			(options
				(clearance outline)
				(anchor circle)
			)
			(primitives
				(gr_poly
					(pts
						(arc
							(start -0.3302 -0.4318)
							(mid -0.402042 -0.402042)
							(end -0.4318 -0.3302)
						)
						(arc
							(start -0.4318 0.3302)
							(mid -0.402042 0.402042)
							(end -0.3302 0.4318)
						)
						(arc
							(start 0.3302 0.4318)
							(mid 0.402042 0.402042)
							(end 0.4318 0.3302)
						)
						(arc
							(start 0.4318 -0.3302)
							(mid 0.402042 -0.402042)
							(end 0.3302 -0.4318)
						)
					)
					(width 0)
					(fill yes)
				)
			)
		)
		(pad "2" smd custom
			(at 0 0.762 180)
			(size 0.2159 0.2159)
			(layers "F.Cu" "F.Mask" "F.Paste")
			(net "GND")
			(options
				(clearance outline)
				(anchor circle)
			)
			(primitives
				(gr_poly
					(pts
						(arc
							(start -0.3302 -0.4318)
							(mid -0.402042 -0.402042)
							(end -0.4318 -0.3302)
						)
						(arc
							(start -0.4318 0.3302)
							(mid -0.402042 0.402042)
							(end -0.3302 0.4318)
						)
						(arc
							(start 0.3302 0.4318)
							(mid 0.402042 0.402042)
							(end 0.4318 0.3302)
						)
						(arc
							(start 0.4318 -0.3302)
							(mid 0.402042 -0.402042)
							(end 0.3302 -0.4318)
						)
					)
					(width 0)
					(fill yes)
				)
			)
		)
	)
)
